(kicad_pcb
	(version 20260206)
	(generator "pcbnew")
	(generator_version "10.0")
	(general
		(thickness 1.6)
		(legacy_teardrops no)
	)
	(paper "A4")
	(title_block
		(title "peb — Lightning_PEB_BRD.brd")
		(comment 1 "Lightning (Wiwynn / Facebook NVMe JBOF) / footprints 2295-2301 of 2563")
	)
	(layers
		(0 "F.Cu" signal "TOP")
		(4 "In1.Cu" signal "L2GND")
		(6 "In2.Cu" signal "L3")
		(8 "In3.Cu" signal "L4VCC")
		(10 "In4.Cu" signal "L5VCC")
		(12 "In5.Cu" signal "L6")
		(14 "In6.Cu" signal "L7GND")
		(2 "B.Cu" signal "BOTTOM")
		(9 "F.Adhes" user "F.Adhesive")
		(11 "B.Adhes" user "B.Adhesive")
		(13 "F.Paste" user "Package Geometry/Pastemask Top")
		(15 "B.Paste" user "Package Geometry/Pastemask Bottom")
		(5 "F.SilkS" user "Ref Des/Silkscreen Top")
		(7 "B.SilkS" user "Ref Des/Silkscreen Bottom")
		(1 "F.Mask" user "Board Geometry/Soldermask Top")
		(3 "B.Mask" user "Board Geometry/Soldermask Bottom")
		(17 "Dwgs.User" user "User.Drawings")
		(19 "Cmts.User" user "User.Comments")
		(21 "Eco1.User" user "User.Eco1")
		(23 "Eco2.User" user "User.Eco2")
		(25 "Edge.Cuts" user "Board Geometry/Outline")
		(27 "Margin" user)
		(31 "F.CrtYd" user "Package Geometry/Place Bound Top")
		(29 "B.CrtYd" user "Package Geometry/Place Bound Bottom")
		(35 "F.Fab" user "Ref Des/Assembly Top")
		(33 "B.Fab" user "Ref Des/Assembly Bottom")
	)
	(footprint ""
		(layer "B.Cu")
		(at 53.721 -136.779 90)
		(property "Reference" "R152"
			(at 0 0 90)
			(layer "B.SilkS")
			(hide yes)
			(effects
				(font
					(size 1.27 1.27)
				)
				(justify mirror)
			)
		)
		(property "Value" "4K7R2F-GP"
			(at -0.064008 -3.993896 90)
			(unlocked yes)
			(layer "B.Fab")
			(hide yes)
			(effects
				(font
					(size 1.016 1.016)
					(thickness 0.1524)
				)
				(justify mirror)
			)
		)
		(property "Device Type" "R402H16"
			(at -0.064008 -5.517896 90)
			(unlocked yes)
			(layer "B.Fab")
			(hide yes)
			(effects
				(font
					(size 1.016 1.016)
					(thickness 0.1524)
				)
				(justify mirror)
			)
		)
		(duplicate_pad_numbers_are_jumpers no)
		(fp_line
			(start 0.508 -0.9398)
			(end 0.508 0.9398)
			(stroke
				(width 0.1524)
				(type default)
			)
			(layer "B.SilkS")
		)
		(fp_line
			(start -0.508 -0.9398)
			(end 0.508 -0.9398)
			(stroke
				(width 0.1524)
				(type default)
			)
			(layer "B.SilkS")
		)
		(fp_rect
			(start 0.508 0.9398)
			(end -0.508 -0.9398)
			(stroke
				(width 0)
				(type default)
			)
			(fill no)
			(layer "B.CrtYd")
		)
		(fp_rect
			(start 0.508 0.9398)
			(end -0.508 -0.9398)
			(stroke
				(width 0)
				(type default)
			)
			(fill no)
			(layer "B.Fab")
		)
		(pad "1" smd custom
			(at 0 -0.4445 270)
			(size 0.1397 0.1397)
			(layers "B.Cu" "B.Mask" "B.Paste")
			(net "CBL_PRSNT_N_2")
			(options
				(clearance outline)
				(anchor circle)
			)
			(primitives
				(gr_poly
					(pts
						(arc
							(start -0.1778 0.2794)
							(mid -0.249642 0.249642)
							(end -0.2794 0.1778)
						)
						(arc
							(start -0.2794 -0.1778)
							(mid -0.249642 -0.249642)
							(end -0.1778 -0.2794)
						)
						(arc
							(start 0.1778 -0.2794)
							(mid 0.249642 -0.249642)
							(end 0.2794 -0.1778)
						)
						(arc
							(start 0.2794 0.1778)
							(mid 0.249642 0.249642)
							(end 0.1778 0.2794)
						)
					)
					(width 0)
					(fill yes)
				)
			)
		)
		(pad "2" smd custom
			(at 0 0.4445 270)
			(size 0.1397 0.1397)
			(layers "B.Cu" "B.Mask" "B.Paste")
			(net "P3V3_STBY")
			(options
				(clearance outline)
				(anchor circle)
			)
			(primitives
				(gr_poly
					(pts
						(arc
							(start -0.1778 0.2794)
							(mid -0.249642 0.249642)
							(end -0.2794 0.1778)
						)
						(arc
							(start -0.2794 -0.1778)
							(mid -0.249642 -0.249642)
							(end -0.1778 -0.2794)
						)
						(arc
							(start 0.1778 -0.2794)
							(mid 0.249642 -0.249642)
							(end 0.2794 -0.1778)
						)
						(arc
							(start 0.2794 0.1778)
							(mid 0.249642 0.249642)
							(end 0.1778 0.2794)
						)
					)
					(width 0)
					(fill yes)
				)
			)
		)
	)
	(footprint ""
		(layer "B.Cu")
		(at 128.524 -202.819)
		(property "Reference" "U65"
			(at 0 0 0)
			(layer "B.SilkS")
			(hide yes)
			(effects
				(font
					(size 1.27 1.27)
				)
				(justify mirror)
			)
		)
		(property "Value" "SN74LVC1G08DCKR-GP"
			(at 2.3368 -8.6868 0)
			(unlocked yes)
			(layer "B.Fab")
			(hide yes)
			(effects
				(font
					(size 1.016 1.016)
					(thickness 0.1524)
				)
				(justify mirror)
			)
		)
		(property "Device Type" "SC70-5H44"
			(at 2.3114 -10.414 0)
			(unlocked yes)
			(layer "B.Fab")
			(hide yes)
			(effects
				(font
					(size 1.016 1.016)
					(thickness 0.1524)
				)
				(justify mirror)
			)
		)
		(duplicate_pad_numbers_are_jumpers no)
		(fp_line
			(start -1.3843 -1.8034)
			(end -1.3843 -1.1176)
			(stroke
				(width 0.3302)
				(type default)
			)
			(layer "B.SilkS")
		)
		(fp_line
			(start -1.27 -1.7018)
			(end -1.27 1.7018)
			(stroke
				(width 0.1524)
				(type default)
			)
			(layer "B.SilkS")
		)
		(fp_line
			(start -1.27 1.7018)
			(end 1.27 1.7018)
			(stroke
				(width 0.1524)
				(type default)
			)
			(layer "B.SilkS")
		)
		(fp_line
			(start -0.6604 -1.8034)
			(end -1.3843 -1.8034)
			(stroke
				(width 0.3302)
				(type default)
			)
			(layer "B.SilkS")
		)
		(fp_line
			(start 1.27 -1.7018)
			(end -1.27 -1.7018)
			(stroke
				(width 0.1524)
				(type default)
			)
			(layer "B.SilkS")
		)
		(fp_line
			(start 1.27 1.7018)
			(end 1.27 -1.7018)
			(stroke
				(width 0.1524)
				(type default)
			)
			(layer "B.SilkS")
		)
		(fp_rect
			(start 1.524 1.9558)
			(end -1.524 -1.9558)
			(stroke
				(width 0)
				(type default)
			)
			(fill no)
			(layer "B.CrtYd")
		)
		(fp_poly
			(pts
				(xy 1.524 -1.9558) (xy -1.524 -1.9558) (xy -1.524 1.9558) (xy 1.524 1.9558)
			)
			(stroke
				(width 0)
				(type default)
			)
			(fill no)
			(layer "B.Fab")
		)
		(pad "1" smd rect
			(at -0.65024 -0.8255 180)
			(size 0.4064 1.2192)
			(layers "B.Cu" "B.Mask" "B.Paste")
			(net "BMC_SSD_RST#0_A1")
		)
		(pad "2" smd rect
			(at 0 -0.8255 180)
			(size 0.4064 1.2192)
			(layers "B.Cu" "B.Mask" "B.Paste")
			(net "SSD_PERST#0_B1")
		)
		(pad "3" smd rect
			(at 0.65024 -0.8255 180)
			(size 0.4064 1.2192)
			(layers "B.Cu" "B.Mask" "B.Paste")
			(net "GND")
		)
		(pad "4" smd rect
			(at 0.65024 0.8255 180)
			(size 0.4064 1.2192)
			(layers "B.Cu" "B.Mask" "B.Paste")
			(net "SSD_PERST_Y1")
		)
		(pad "5" smd rect
			(at -0.65024 0.8255 180)
			(size 0.4064 1.2192)
			(layers "B.Cu" "B.Mask" "B.Paste")
			(net "P3V3_STBY")
		)
	)
	(footprint ""
		(layer "B.Cu")
		(at 265.216894 -4.970272)
		(property "Reference" "R189"
			(at 0 0 0)
			(layer "B.SilkS")
			(hide yes)
			(effects
				(font
					(size 1.27 1.27)
				)
				(justify mirror)
			)
		)
		(property "Value" "4K7R2F-GP"
			(at -0.064008 -3.993896 0)
			(unlocked yes)
			(layer "B.Fab")
			(hide yes)
			(effects
				(font
					(size 1.016 1.016)
					(thickness 0.1524)
				)
				(justify mirror)
			)
		)
		(property "Device Type" "R402H16"
			(at -0.064008 -5.517896 0)
			(unlocked yes)
			(layer "B.Fab")
			(hide yes)
			(effects
				(font
					(size 1.016 1.016)
					(thickness 0.1524)
				)
				(justify mirror)
			)
		)
		(duplicate_pad_numbers_are_jumpers no)
		(fp_line
			(start -0.508 -0.9398)
			(end 0.508 -0.9398)
			(stroke
				(width 0.1524)
				(type default)
			)
			(layer "B.SilkS")
		)
		(fp_line
			(start 0.508 -0.9398)
			(end 0.508 0.9398)
			(stroke
				(width 0.1524)
				(type default)
			)
			(layer "B.SilkS")
		)
		(fp_rect
			(start 0.508 0.9398)
			(end -0.508 -0.9398)
			(stroke
				(width 0)
				(type default)
			)
			(fill no)
			(layer "B.CrtYd")
		)
		(fp_rect
			(start 0.508 0.9398)
			(end -0.508 -0.9398)
			(stroke
				(width 0)
				(type default)
			)
			(fill no)
			(layer "B.Fab")
		)
		(pad "1" smd custom
			(at 0 -0.4445 180)
			(size 0.1397 0.1397)
			(layers "B.Cu" "B.Mask" "B.Paste")
			(net "P3V3_STBY")
			(options
				(clearance outline)
				(anchor circle)
			)
			(primitives
				(gr_poly
					(pts
						(arc
							(start -0.1778 0.2794)
							(mid -0.249642 0.249642)
							(end -0.2794 0.1778)
						)
						(arc
							(start -0.2794 -0.1778)
							(mid -0.249642 -0.249642)
							(end -0.1778 -0.2794)
						)
						(arc
							(start 0.1778 -0.2794)
							(mid 0.249642 -0.249642)
							(end 0.2794 -0.1778)
						)
						(arc
							(start 0.2794 0.1778)
							(mid 0.249642 0.249642)
							(end 0.1778 0.2794)
						)
					)
					(width 0)
					(fill yes)
				)
			)
		)
		(pad "2" smd custom
			(at 0 0.4445 180)
			(size 0.1397 0.1397)
			(layers "B.Cu" "B.Mask" "B.Paste")
			(net "TEMP_1_A1")
			(options
				(clearance outline)
				(anchor circle)
			)
			(primitives
				(gr_poly
					(pts
						(arc
							(start -0.1778 0.2794)
							(mid -0.249642 0.249642)
							(end -0.2794 0.1778)
						)
						(arc
							(start -0.2794 -0.1778)
							(mid -0.249642 -0.249642)
							(end -0.1778 -0.2794)
						)
						(arc
							(start 0.1778 -0.2794)
							(mid 0.249642 -0.249642)
							(end 0.2794 -0.1778)
						)
						(arc
							(start 0.2794 0.1778)
							(mid 0.249642 0.249642)
							(end 0.1778 0.2794)
						)
					)
					(width 0)
					(fill yes)
				)
			)
		)
	)
	(footprint ""
		(layer "B.Cu")
		(at 235.331 -67.818 -90)
		(property "Reference" "C516"
			(at 0 0 90)
			(layer "B.SilkS")
			(hide yes)
			(effects
				(font
					(size 1.27 1.27)
				)
				(justify mirror)
			)
		)
		(property "Value" "SC4D7U16V5KX-1-GP"
			(at 0.0762 -6.1214 270)
			(unlocked yes)
			(layer "B.Fab")
			(hide yes)
			(effects
				(font
					(size 1.016 1.016)
					(thickness 0.1524)
				)
				(justify mirror)
			)
		)
		(property "Device Type" "C805H56"
			(at 0.0762 -8.1534 270)
			(unlocked yes)
			(layer "B.Fab")
			(hide yes)
			(effects
				(font
					(size 1.016 1.016)
					(thickness 0.1524)
				)
				(justify mirror)
			)
		)
		(duplicate_pad_numbers_are_jumpers no)
		(fp_line
			(start -0.635 0)
			(end 0.635 0)
			(stroke
				(width 0.508)
				(type default)
			)
			(layer "B.SilkS")
		)
		(fp_rect
			(start 0.9652 1.778)
			(end -0.9652 -1.778)
			(stroke
				(width 0)
				(type default)
			)
			(fill no)
			(layer "B.CrtYd")
		)
		(fp_poly
			(pts
				(xy 0.9652 -1.778) (xy -0.9652 -1.778) (xy -0.9652 1.778) (xy 0.9652 1.778)
			)
			(stroke
				(width 0)
				(type default)
			)
			(fill no)
			(layer "B.Fab")
		)
		(pad "1" smd rect
			(at 0 -0.9652 90)
			(size 1.397 1.143)
			(layers "B.Cu" "B.Mask" "B.Paste")
			(net "DUT_AVD_TX")
		)
		(pad "2" smd rect
			(at 0 0.9652 90)
			(size 1.397 1.143)
			(layers "B.Cu" "B.Mask" "B.Paste")
			(net "GND")
		)
	)
	(footprint ""
		(layer "B.Cu")
		(at 247.65 -44.9961 -90)
		(property "Reference" "C595"
			(at 0 0 90)
			(layer "B.SilkS")
			(hide yes)
			(effects
				(font
					(size 1.27 1.27)
				)
				(justify mirror)
			)
		)
		(property "Value" "SCD1U16V1KX-1-GP"
			(at 2.8321 -1.7399 270)
			(unlocked yes)
			(layer "B.Fab")
			(hide yes)
			(effects
				(font
					(size 1.016 1.016)
					(thickness 0.1524)
				)
				(justify mirror)
			)
		)
		(property "Device Type" "C0201H13"
			(at 2.8321 -3.2639 270)
			(unlocked yes)
			(layer "B.Fab")
			(hide yes)
			(effects
				(font
					(size 1.016 1.016)
					(thickness 0.1524)
				)
				(justify mirror)
			)
		)
		(duplicate_pad_numbers_are_jumpers no)
		(fp_rect
			(start 0.2794 0.6477)
			(end -0.2794 -0.6477)
			(stroke
				(width 0)
				(type default)
			)
			(fill no)
			(layer "B.CrtYd")
		)
		(fp_rect
			(start 0.2794 0.6477)
			(end -0.2794 -0.6477)
			(stroke
				(width 0)
				(type default)
			)
			(fill no)
			(layer "B.Fab")
		)
		(pad "1" smd custom
			(at 0 -0.2794 90)
			(size 0.0762 0.0762)
			(layers "B.Cu" "B.Mask" "B.Paste")
			(net "DUT_AVD_PCIE")
			(options
				(clearance outline)
				(anchor circle)
			)
			(primitives
				(gr_poly
					(pts
						(arc
							(start 0.1524 0.127)
							(mid 0.137521 0.162921)
							(end 0.1016 0.1778)
						)
						(arc
							(start -0.1016 0.1778)
							(mid -0.137521 0.162921)
							(end -0.1524 0.127)
						)
						(arc
							(start -0.1524 -0.127)
							(mid -0.137521 -0.162921)
							(end -0.1016 -0.1778)
						)
						(arc
							(start 0.1016 -0.1778)
							(mid 0.137521 -0.162921)
							(end 0.1524 -0.127)
						)
					)
					(width 0)
					(fill yes)
				)
			)
		)
		(pad "2" smd custom
			(at 0 0.2794 90)
			(size 0.0762 0.0762)
			(layers "B.Cu" "B.Mask" "B.Paste")
			(net "GND")
			(options
				(clearance outline)
				(anchor circle)
			)
			(primitives
				(gr_poly
					(pts
						(arc
							(start 0.1524 0.127)
							(mid 0.137521 0.162921)
							(end 0.1016 0.1778)
						)
						(arc
							(start -0.1016 0.1778)
							(mid -0.137521 0.162921)
							(end -0.1524 0.127)
						)
						(arc
							(start -0.1524 -0.127)
							(mid -0.137521 -0.162921)
							(end -0.1016 -0.1778)
						)
						(arc
							(start 0.1016 -0.1778)
							(mid 0.137521 -0.162921)
							(end 0.1524 -0.127)
						)
					)
					(width 0)
					(fill yes)
				)
			)
		)
	)
	(footprint ""
		(layer "B.Cu")
		(at 339.884512 -184.878218 180)
		(property "Reference" "R4150"
			(at 0 0 0)
			(layer "B.SilkS")
			(hide yes)
			(effects
				(font
					(size 1.27 1.27)
				)
				(justify mirror)
			)
		)
		(property "Value" "4K7R2F-GP"
			(at -0.064008 -3.993896 180)
			(unlocked yes)
			(layer "B.Fab")
			(hide yes)
			(effects
				(font
					(size 1.016 1.016)
					(thickness 0.1524)
				)
				(justify mirror)
			)
		)
		(property "Device Type" "R402H16"
			(at -0.064008 -5.517896 180)
			(unlocked yes)
			(layer "B.Fab")
			(hide yes)
			(effects
				(font
					(size 1.016 1.016)
					(thickness 0.1524)
				)
				(justify mirror)
			)
		)
		(duplicate_pad_numbers_are_jumpers no)
		(fp_line
			(start 0.508 -0.9398)
			(end 0.508 0.9398)
			(stroke
				(width 0.1524)
				(type default)
			)
			(layer "B.SilkS")
		)
		(fp_line
			(start -0.508 -0.9398)
			(end 0.508 -0.9398)
			(stroke
				(width 0.1524)
				(type default)
			)
			(layer "B.SilkS")
		)
		(fp_rect
			(start 0.508 0.9398)
			(end -0.508 -0.9398)
			(stroke
				(width 0)
				(type default)
			)
			(fill no)
			(layer "B.CrtYd")
		)
		(fp_rect
			(start 0.508 0.9398)
			(end -0.508 -0.9398)
			(stroke
				(width 0)
				(type default)
			)
			(fill no)
			(layer "B.Fab")
		)
		(pad "1" smd custom
			(at 0 -0.4445)
			(size 0.1397 0.1397)
			(layers "B.Cu" "B.Mask" "B.Paste")
			(net "SSD_PRSNT#14")
			(options
				(clearance outline)
				(anchor circle)
			)
			(primitives
				(gr_poly
					(pts
						(arc
							(start -0.1778 0.2794)
							(mid -0.249642 0.249642)
							(end -0.2794 0.1778)
						)
						(arc
							(start -0.2794 -0.1778)
							(mid -0.249642 -0.249642)
							(end -0.1778 -0.2794)
						)
						(arc
							(start 0.1778 -0.2794)
							(mid 0.249642 -0.249642)
							(end 0.2794 -0.1778)
						)
						(arc
							(start 0.2794 0.1778)
							(mid 0.249642 0.249642)
							(end 0.1778 0.2794)
						)
					)
					(width 0)
					(fill yes)
				)
			)
		)
		(pad "2" smd custom
			(at 0 0.4445)
			(size 0.1397 0.1397)
			(layers "B.Cu" "B.Mask" "B.Paste")
			(net "P3V3_STBY")
			(options
				(clearance outline)
				(anchor circle)
			)
			(primitives
				(gr_poly
					(pts
						(arc
							(start -0.1778 0.2794)
							(mid -0.249642 0.249642)
							(end -0.2794 0.1778)
						)
						(arc
							(start -0.2794 -0.1778)
							(mid -0.249642 -0.249642)
							(end -0.1778 -0.2794)
						)
						(arc
							(start 0.1778 -0.2794)
							(mid 0.249642 -0.249642)
							(end 0.2794 -0.1778)
						)
						(arc
							(start 0.2794 0.1778)
							(mid 0.249642 0.249642)
							(end 0.1778 0.2794)
						)
					)
					(width 0)
					(fill yes)
				)
			)
		)
	)
	(footprint ""
		(layer "B.Cu")
		(at 263.10082 -2.341626 180)
		(property "Reference" "R201"
			(at 0 0 0)
			(layer "B.SilkS")
			(hide yes)
			(effects
				(font
					(size 1.27 1.27)
				)
				(justify mirror)
			)
		)
		(property "Value" "49D9R2D-GP"
			(at -0.064008 -3.993896 180)
			(unlocked yes)
			(layer "B.Fab")
			(hide yes)
			(effects
				(font
					(size 1.016 1.016)
					(thickness 0.1524)
				)
				(justify mirror)
			)
		)
		(property "Device Type" "R402H16"
			(at -0.064008 -5.517896 180)
			(unlocked yes)
			(layer "B.Fab")
			(hide yes)
			(effects
				(font
					(size 1.016 1.016)
					(thickness 0.1524)
				)
				(justify mirror)
			)
		)
		(duplicate_pad_numbers_are_jumpers no)
		(fp_line
			(start 0.508 -0.9398)
			(end 0.508 0.9398)
			(stroke
				(width 0.1524)
				(type default)
			)
			(layer "B.SilkS")
		)
		(fp_line
			(start -0.508 -0.9398)
			(end 0.508 -0.9398)
			(stroke
				(width 0.1524)
				(type default)
			)
			(layer "B.SilkS")
		)
		(fp_rect
			(start 0.508 0.9398)
			(end -0.508 -0.9398)
			(stroke
				(width 0)
				(type default)
			)
			(fill no)
			(layer "B.CrtYd")
		)
		(fp_rect
			(start 0.508 0.9398)
			(end -0.508 -0.9398)
			(stroke
				(width 0)
				(type default)
			)
			(fill no)
			(layer "B.Fab")
		)
		(pad "1" smd custom
			(at 0 -0.4445)
			(size 0.1397 0.1397)
			(layers "B.Cu" "B.Mask" "B.Paste")
			(net "TEMP_SENSOR_DXP_R")
			(options
				(clearance outline)
				(anchor circle)
			)
			(primitives
				(gr_poly
					(pts
						(arc
							(start -0.1778 0.2794)
							(mid -0.249642 0.249642)
							(end -0.2794 0.1778)
						)
						(arc
							(start -0.2794 -0.1778)
							(mid -0.249642 -0.249642)
							(end -0.1778 -0.2794)
						)
						(arc
							(start 0.1778 -0.2794)
							(mid 0.249642 -0.249642)
							(end 0.2794 -0.1778)
						)
						(arc
							(start 0.2794 0.1778)
							(mid 0.249642 0.249642)
							(end 0.1778 0.2794)
						)
					)
					(width 0)
					(fill yes)
				)
			)
		)
		(pad "2" smd custom
			(at 0 0.4445)
			(size 0.1397 0.1397)
			(layers "B.Cu" "B.Mask" "B.Paste")
			(net "TEMP_SENSOR_DXP")
			(options
				(clearance outline)
				(anchor circle)
			)
			(primitives
				(gr_poly
					(pts
						(arc
							(start -0.1778 0.2794)
							(mid -0.249642 0.249642)
							(end -0.2794 0.1778)
						)
						(arc
							(start -0.2794 -0.1778)
							(mid -0.249642 -0.249642)
							(end -0.1778 -0.2794)
						)
						(arc
							(start 0.1778 -0.2794)
							(mid 0.249642 -0.249642)
							(end 0.2794 -0.1778)
						)
						(arc
							(start 0.2794 0.1778)
							(mid 0.249642 0.249642)
							(end 0.1778 0.2794)
						)
					)
					(width 0)
					(fill yes)
				)
			)
		)
	)
)
